# S9S_MB_2U (Grand Teton) — schematic netlist excerpt (pin names and nets, part order shuffled) for the footprints in the layout excerpt that follows; sources: Cadence DE-HDL packaged netlist, KiCad conversion of 03242023_DA0F0TMBIJ0_F0T_Motherboard_J_brd_V01_OCP.brd

PC1420  Q_CAP  0.01UF 25V 10% X7R  pkg 0402  page 282 : A = PVNN_MAIN_CPU0_FB_RC ; B = GND
R1275  Q_RES  22 1% CHIP  pkg 0402LF  page 209 : A = CLK_100M_OCP_SFF_3_R_DP ; B = CLK_100M_OCP_SFF_3_DP

(kicad_pcb
	(version 20260206)
	(generator "pcbnew")
	(generator_version "10.0")
	(general
		(thickness 1.6)
		(legacy_teardrops no)
	)
	(paper "A4")
	(title_block
		(title "03242023_DA0F0TMBIJ0_F0T_Motherboard_J_brd_V01_OCP.brd")
		(comment 1 "Grand Teton / footprints 2967-2968 of 6105")
	)
	(layers
		(0 "F.Cu" signal "TOP")
		(4 "In1.Cu" signal "GND")
		(6 "In2.Cu" signal "IN1")
		(8 "In3.Cu" signal "GND1")
		(10 "In4.Cu" signal "IN2")
		(12 "In5.Cu" signal "GND2")
		(14 "In6.Cu" signal "IN3")
		(16 "In7.Cu" signal "GND3")
		(18 "In8.Cu" signal "VCC")
		(20 "In9.Cu" signal "VCC1")
		(22 "In10.Cu" signal "GND4")
		(24 "In11.Cu" signal "IN4")
		(26 "In12.Cu" signal "GND5")
		(28 "In13.Cu" signal "IN5")
		(30 "In14.Cu" signal "GND6")
		(32 "In15.Cu" signal "IN6")
		(34 "In16.Cu" signal "GND7")
		(2 "B.Cu" signal "BOTTOM")
		(9 "F.Adhes" user "F.Adhesive")
		(11 "B.Adhes" user "B.Adhesive")
		(13 "F.Paste" user "Package Geometry/Pastemask Top")
		(15 "B.Paste" user "Package Geometry/Pastemask Bottom")
		(5 "F.SilkS" user "Ref Des/Silkscreen Top")
		(7 "B.SilkS" user "Ref Des/Silkscreen Bottom")
		(1 "F.Mask" user "Board Geometry/Soldermask Top")
		(3 "B.Mask" user "Board Geometry/Soldermask Bottom")
		(17 "Dwgs.User" user "User.Drawings")
		(19 "Cmts.User" user "User.Comments")
		(21 "Eco1.User" user "User.Eco1")
		(23 "Eco2.User" user "User.Eco2")
		(25 "Edge.Cuts" user "Board Geometry/Outline")
		(27 "Margin" user)
		(31 "F.CrtYd" user "Package Geometry/Place Bound Top")
		(29 "B.CrtYd" user "Package Geometry/Place Bound Bottom")
		(35 "F.Fab" user "Ref Des/Assembly Top")
		(33 "B.Fab" user "Ref Des/Assembly Bottom")
	)
	(footprint ""
		(layer "F.Cu")
		(at 230.960422 -117.710712 -90)
		(property "Reference" "R1275"
			(at 0 0 270)
			(layer "F.SilkS")
			(hide yes)
			(effects
				(font
					(size 1.27 1.27)
				)
			)
		)
		(property "Value" ""
			(at 0 0 270)
			(layer "F.Fab")
			(effects
				(font
					(size 1.27 1.27)
				)
			)
		)
		(duplicate_pad_numbers_are_jumpers no)
		(fp_line
			(start -0.7874 0.4064)
			(end -0.7874 0.000762)
			(stroke
				(width 0.1524)
				(type default)
			)
			(layer "F.SilkS")
		)
		(fp_line
			(start 0.7874 0.4064)
			(end -0.7874 0.4064)
			(stroke
				(width 0.1524)
				(type default)
			)
			(layer "F.SilkS")
		)
		(fp_line
			(start 0.7874 -0.095758)
			(end 0.7874 0.4064)
			(stroke
				(width 0.1524)
				(type default)
			)
			(layer "F.SilkS")
		)
		(fp_line
			(start -0.373888 -0.4064)
			(end 0.418592 -0.4064)
			(stroke
				(width 0.1524)
				(type default)
			)
			(layer "F.SilkS")
		)
		(fp_line
			(start -0.67945 0.3048)
			(end -0.67945 -0.305054)
			(stroke
				(width 0.1)
				(type default)
			)
			(layer "F.Fab")
		)
		(fp_line
			(start -0.12065 0.3048)
			(end -0.67945 0.3048)
			(stroke
				(width 0.1)
				(type default)
			)
			(layer "F.Fab")
		)
		(fp_line
			(start 0.120396 0.3048)
			(end 0.120396 0.2794)
			(stroke
				(width 0.1)
				(type default)
			)
			(layer "F.Fab")
		)
		(fp_line
			(start 0.67945 0.3048)
			(end 0.120396 0.3048)
			(stroke
				(width 0.1)
				(type default)
			)
			(layer "F.Fab")
		)
		(fp_line
			(start -0.12065 0.2794)
			(end -0.12065 0.3048)
			(stroke
				(width 0.1)
				(type default)
			)
			(layer "F.Fab")
		)
		(fp_line
			(start 0.120396 0.2794)
			(end -0.12065 0.2794)
			(stroke
				(width 0.1)
				(type default)
			)
			(layer "F.Fab")
		)
		(fp_line
			(start -0.12065 -0.2794)
			(end 0.12065 -0.2794)
			(stroke
				(width 0.1)
				(type default)
			)
			(layer "F.Fab")
		)
		(fp_line
			(start 0.12065 -0.2794)
			(end 0.12065 -0.3048)
			(stroke
				(width 0.1)
				(type default)
			)
			(layer "F.Fab")
		)
		(fp_line
			(start 0.12065 -0.3048)
			(end 0.67945 -0.3048)
			(stroke
				(width 0.1)
				(type default)
			)
			(layer "F.Fab")
		)
		(fp_line
			(start 0.67945 -0.3048)
			(end 0.67945 0.3048)
			(stroke
				(width 0.1)
				(type default)
			)
			(layer "F.Fab")
		)
		(fp_line
			(start -0.67945 -0.305054)
			(end -0.12065 -0.305054)
			(stroke
				(width 0.1)
				(type default)
			)
			(layer "F.Fab")
		)
		(fp_line
			(start -0.12065 -0.305054)
			(end -0.12065 -0.2794)
			(stroke
				(width 0.1)
				(type default)
			)
			(layer "F.Fab")
		)
		(pad "1" smd circle
			(at -0.40005 0 270)
			(size 0 0)
			(layers "F.Cu" "F.Mask" "F.Paste")
			(net "CLK_100M_OCP_SFF_3_R_DP")
		)
		(pad "2" smd circle
			(at 0.40005 0 270)
			(size 0 0)
			(layers "F.Cu" "F.Mask" "F.Paste")
			(net "CLK_100M_OCP_SFF_3_DP")
		)
	)
	(footprint ""
		(layer "F.Cu")
		(at 433.83962 -175.197008 90)
		(property "Reference" "PC1420"
			(at 0 0 90)
			(layer "F.SilkS")
			(hide yes)
			(effects
				(font
					(size 1.27 1.27)
				)
			)
		)
		(property "Value" ""
			(at 0 0 90)
			(layer "F.Fab")
			(effects
				(font
					(size 1.27 1.27)
				)
			)
		)
		(duplicate_pad_numbers_are_jumpers no)
		(fp_line
			(start 0.7874 -0.4064)
			(end 0.7874 0.4064)
			(stroke
				(width 0.1524)
				(type default)
			)
			(layer "F.SilkS")
		)
		(fp_line
			(start -0.7874 -0.4064)
			(end 0.7874 -0.4064)
			(stroke
				(width 0.1524)
				(type default)
			)
			(layer "F.SilkS")
		)
		(fp_line
			(start 0.7874 0.4064)
			(end -0.7874 0.4064)
			(stroke
				(width 0.1524)
				(type default)
			)
			(layer "F.SilkS")
		)
		(fp_line
			(start -0.7874 0.4064)
			(end -0.7874 -0.4064)
			(stroke
				(width 0.1524)
				(type default)
			)
			(layer "F.SilkS")
		)
		(fp_line
			(start -0.12065 -0.305054)
			(end -0.12065 -0.2794)
			(stroke
				(width 0.1)
				(type default)
			)
			(layer "F.Fab")
		)
		(fp_line
			(start -0.67945 -0.305054)
			(end -0.12065 -0.305054)
			(stroke
				(width 0.1)
				(type default)
			)
			(layer "F.Fab")
		)
		(fp_line
			(start 0.67945 -0.3048)
			(end 0.67945 0.3048)
			(stroke
				(width 0.1)
				(type default)
			)
			(layer "F.Fab")
		)
		(fp_line
			(start 0.12065 -0.3048)
			(end 0.67945 -0.3048)
			(stroke
				(width 0.1)
				(type default)
			)
			(layer "F.Fab")
		)
		(fp_line
			(start 0.12065 -0.2794)
			(end 0.12065 -0.3048)
			(stroke
				(width 0.1)
				(type default)
			)
			(layer "F.Fab")
		)
		(fp_line
			(start -0.12065 -0.2794)
			(end 0.12065 -0.2794)
			(stroke
				(width 0.1)
				(type default)
			)
			(layer "F.Fab")
		)
		(fp_line
			(start 0.120396 0.2794)
			(end -0.12065 0.2794)
			(stroke
				(width 0.1)
				(type default)
			)
			(layer "F.Fab")
		)
		(fp_line
			(start -0.12065 0.2794)
			(end -0.12065 0.3048)
			(stroke
				(width 0.1)
				(type default)
			)
			(layer "F.Fab")
		)
		(fp_line
			(start 0.67945 0.3048)
			(end 0.120396 0.3048)
			(stroke
				(width 0.1)
				(type default)
			)
			(layer "F.Fab")
		)
		(fp_line
			(start 0.120396 0.3048)
			(end 0.120396 0.2794)
			(stroke
				(width 0.1)
				(type default)
			)
			(layer "F.Fab")
		)
		(fp_line
			(start -0.12065 0.3048)
			(end -0.67945 0.3048)
			(stroke
				(width 0.1)
				(type default)
			)
			(layer "F.Fab")
		)
		(fp_line
			(start -0.67945 0.3048)
			(end -0.67945 -0.305054)
			(stroke
				(width 0.1)
				(type default)
			)
			(layer "F.Fab")
		)
		(pad "1" smd circle
			(at -0.40005 0 90)
			(size 0 0)
			(layers "F.Cu" "F.Mask" "F.Paste")
			(net "PVNN_MAIN_CPU0_FB_RC")
		)
		(pad "2" smd circle
			(at 0.40005 0 90)
			(size 0 0)
			(layers "F.Cu" "F.Mask" "F.Paste")
			(net "GND")
		)
	)
)
